(kicad_pcb
	(version 20260206)
	(generator "pcbnew")
	(generator_version "10.0")
	(general
		(thickness 1.6)
		(legacy_teardrops no)
	)
	(paper "A4")
	(title_block
		(title "peb — Lightning_PEB_BRD.brd")
		(comment 1 "Lightning (Wiwynn / Facebook NVMe JBOF) / footprints 387-392 of 2563")
	)
	(layers
		(0 "F.Cu" signal "TOP")
		(4 "In1.Cu" signal "L2GND")
		(6 "In2.Cu" signal "L3")
		(8 "In3.Cu" signal "L4VCC")
		(10 "In4.Cu" signal "L5VCC")
		(12 "In5.Cu" signal "L6")
		(14 "In6.Cu" signal "L7GND")
		(2 "B.Cu" signal "BOTTOM")
		(9 "F.Adhes" user "F.Adhesive")
		(11 "B.Adhes" user "B.Adhesive")
		(13 "F.Paste" user "Package Geometry/Pastemask Top")
		(15 "B.Paste" user "Package Geometry/Pastemask Bottom")
		(5 "F.SilkS" user "Ref Des/Silkscreen Top")
		(7 "B.SilkS" user "Ref Des/Silkscreen Bottom")
		(1 "F.Mask" user "Board Geometry/Soldermask Top")
		(3 "B.Mask" user "Board Geometry/Soldermask Bottom")
		(17 "Dwgs.User" user "User.Drawings")
		(19 "Cmts.User" user "User.Comments")
		(21 "Eco1.User" user "User.Eco1")
		(23 "Eco2.User" user "User.Eco2")
		(25 "Edge.Cuts" user "Board Geometry/Outline")
		(27 "Margin" user)
		(31 "F.CrtYd" user "Package Geometry/Place Bound Top")
		(29 "B.CrtYd" user "Package Geometry/Place Bound Bottom")
		(35 "F.Fab" user "Ref Des/Assembly Top")
		(33 "B.Fab" user "Ref Des/Assembly Bottom")
	)
	(footprint ""
		(layer "F.Cu")
		(at 133.453886 -83.957414 180)
		(property "Reference" "C307"
			(at 0 0 180)
			(layer "F.SilkS")
			(hide yes)
			(effects
				(font
					(size 1.27 1.27)
				)
			)
		)
		(property "Value" "SC15P50V2JN-2-GP"
			(at 1.1811 -2.7051 180)
			(unlocked yes)
			(layer "F.Fab")
			(hide yes)
			(effects
				(font
					(size 1.016 1.016)
					(thickness 0.1524)
				)
			)
		)
		(property "Device Type" "C402H22"
			(at 1.1811 -4.2291 180)
			(unlocked yes)
			(layer "F.Fab")
			(hide yes)
			(effects
				(font
					(size 1.016 1.016)
					(thickness 0.1524)
				)
			)
		)
		(duplicate_pad_numbers_are_jumpers no)
		(fp_rect
			(start -0.4318 0.9525)
			(end 0.4318 -0.9525)
			(stroke
				(width 0)
				(type default)
			)
			(fill no)
			(layer "F.CrtYd")
		)
		(fp_rect
			(start -0.4318 0.9525)
			(end 0.4318 -0.9525)
			(stroke
				(width 0)
				(type default)
			)
			(fill no)
			(layer "F.Fab")
		)
		(pad "1" smd custom
			(at 0 -0.4445 180)
			(size 0.1524 0.1524)
			(layers "F.Cu" "F.Mask" "F.Paste")
			(net "RTC_OSCO")
			(options
				(clearance outline)
				(anchor circle)
			)
			(primitives
				(gr_poly
					(pts
						(arc
							(start 0.3048 -0.2032)
							(mid 0.275042 -0.275042)
							(end 0.2032 -0.3048)
						)
						(arc
							(start -0.2032 -0.3048)
							(mid -0.275042 -0.275042)
							(end -0.3048 -0.2032)
						)
						(arc
							(start -0.3048 0.2032)
							(mid -0.275042 0.275042)
							(end -0.2032 0.3048)
						)
						(arc
							(start 0.2032 0.3048)
							(mid 0.275042 0.275042)
							(end 0.3048 0.2032)
						)
					)
					(width 0)
					(fill yes)
				)
			)
		)
		(pad "2" smd custom
			(at 0 0.4445 180)
			(size 0.1524 0.1524)
			(layers "F.Cu" "F.Mask" "F.Paste")
			(net "GND")
			(options
				(clearance outline)
				(anchor circle)
			)
			(primitives
				(gr_poly
					(pts
						(arc
							(start 0.3048 -0.2032)
							(mid 0.275042 -0.275042)
							(end 0.2032 -0.3048)
						)
						(arc
							(start -0.2032 -0.3048)
							(mid -0.275042 -0.275042)
							(end -0.3048 -0.2032)
						)
						(arc
							(start -0.3048 0.2032)
							(mid -0.275042 0.275042)
							(end -0.2032 0.3048)
						)
						(arc
							(start 0.2032 0.3048)
							(mid 0.275042 0.275042)
							(end 0.3048 0.2032)
						)
					)
					(width 0)
					(fill yes)
				)
			)
		)
	)
	(footprint ""
		(layer "F.Cu")
		(at 222.226124 -196.951092)
		(property "Reference" "U200"
			(at 0 0 0)
			(layer "F.SilkS")
			(hide yes)
			(effects
				(font
					(size 1.27 1.27)
				)
			)
		)
		(property "Value" "MAX7311AUG-GP"
			(at 0 -12.1412 0)
			(unlocked yes)
			(layer "F.Fab")
			(hide yes)
			(effects
				(font
					(size 1.016 1.016)
					(thickness 0.1524)
				)
			)
		)
		(property "Device Type" "TSOIC24H44"
			(at 0 -13.6652 0)
			(unlocked yes)
			(layer "F.Fab")
			(hide yes)
			(effects
				(font
					(size 1.016 1.016)
					(thickness 0.1524)
				)
			)
		)
		(duplicate_pad_numbers_are_jumpers no)
		(fp_line
			(start -4.1148 -1.778)
			(end -4.1148 1.778)
			(stroke
				(width 0.1524)
				(type default)
			)
			(layer "F.SilkS")
		)
		(fp_line
			(start -4.1148 -1.778)
			(end 3.683 -1.778)
			(stroke
				(width 0.1524)
				(type default)
			)
			(layer "F.SilkS")
		)
		(fp_line
			(start -4.0386 1.778)
			(end -4.0386 3.556)
			(stroke
				(width 0.3556)
				(type default)
			)
			(layer "F.SilkS")
		)
		(fp_line
			(start -3.8354 0)
			(end -4.1148 -0.2794)
			(stroke
				(width 0.1524)
				(type default)
			)
			(layer "F.SilkS")
		)
		(fp_line
			(start -3.8354 0)
			(end -4.1148 0.2794)
			(stroke
				(width 0.1524)
				(type default)
			)
			(layer "F.SilkS")
		)
		(fp_line
			(start 3.683 -1.778)
			(end 3.683 1.778)
			(stroke
				(width 0.1524)
				(type default)
			)
			(layer "F.SilkS")
		)
		(fp_line
			(start 3.683 1.778)
			(end -4.1148 1.778)
			(stroke
				(width 0.1524)
				(type default)
			)
			(layer "F.SilkS")
		)
		(fp_poly
			(pts
				(xy -3.7592 -1.778) (xy 3.683 -1.778) (xy 3.683 1.778) (xy -3.7592 1.778)
			)
			(stroke
				(width 0)
				(type default)
			)
			(fill yes)
			(layer "F.SilkS")
		)
		(fp_poly
			(pts
				(xy -4.22656 3.81) (xy 4.22656 3.81) (xy 4.22656 -3.81) (xy -4.22656 -3.81)
			)
			(stroke
				(width 0)
				(type default)
			)
			(fill no)
			(layer "F.CrtYd")
		)
		(fp_poly
			(pts
				(xy -4.22656 -3.81) (xy 4.22656 -3.81) (xy 4.22656 3.81) (xy -4.22656 3.81)
			)
			(stroke
				(width 0)
				(type default)
			)
			(fill no)
			(layer "F.Fab")
		)
		(pad "1" smd rect
			(at -3.57632 2.8194)
			(size 0.3556 1.524)
			(layers "F.Cu" "F.Mask" "F.Paste")
			(net "IOEXP_INT#_3")
		)
		(pad "2" smd rect
			(at -2.92608 2.8194)
			(size 0.3556 1.524)
			(layers "F.Cu" "F.Mask" "F.Paste")
			(net "IOEXP3_AD1")
		)
		(pad "3" smd rect
			(at -2.27584 2.8194)
			(size 0.3556 1.524)
			(layers "F.Cu" "F.Mask" "F.Paste")
			(net "IOEXP3_AD2")
		)
		(pad "4" smd rect
			(at -1.6256 2.8194)
			(size 0.3556 1.524)
			(layers "F.Cu" "F.Mask" "F.Paste")
			(net "SSD_PRSNT#3")
		)
		(pad "5" smd rect
			(at -0.97536 2.8194)
			(size 0.3556 1.524)
			(layers "F.Cu" "F.Mask" "F.Paste")
			(net "SSD_ATNLED#3")
		)
		(pad "6" smd rect
			(at -0.32512 2.8194)
			(size 0.3556 1.524)
			(layers "F.Cu" "F.Mask" "F.Paste")
			(net "SSD_PWREN3")
		)
		(pad "7" smd rect
			(at 0.32512 2.8194)
			(size 0.3556 1.524)
			(layers "F.Cu" "F.Mask" "F.Paste")
			(net "SSD_PERST#3")
		)
		(pad "8" smd rect
			(at 0.97536 2.8194)
			(size 0.3556 1.524)
			(layers "F.Cu" "F.Mask" "F.Paste")
			(net "SSD_PRSNT#8")
		)
		(pad "9" smd rect
			(at 1.6256 2.8194)
			(size 0.3556 1.524)
			(layers "F.Cu" "F.Mask" "F.Paste")
			(net "SSD_ATNLED#8")
		)
		(pad "10" smd rect
			(at 2.27584 2.8194)
			(size 0.3556 1.524)
			(layers "F.Cu" "F.Mask" "F.Paste")
			(net "SSD_PWREN8")
		)
		(pad "11" smd rect
			(at 2.92608 2.8194)
			(size 0.3556 1.524)
			(layers "F.Cu" "F.Mask" "F.Paste")
			(net "SSD_PERST#8")
		)
		(pad "12" smd rect
			(at 3.57632 2.8194)
			(size 0.3556 1.524)
			(layers "F.Cu" "F.Mask" "F.Paste")
			(net "GND")
		)
		(pad "13" smd rect
			(at 3.57632 -2.8194)
			(size 0.3556 1.524)
			(layers "F.Cu" "F.Mask" "F.Paste")
			(net "SSD_PRSNT#12")
		)
		(pad "14" smd rect
			(at 2.92608 -2.8194)
			(size 0.3556 1.524)
			(layers "F.Cu" "F.Mask" "F.Paste")
			(net "SSD_ATNLED#12")
		)
		(pad "15" smd rect
			(at 2.27584 -2.8194)
			(size 0.3556 1.524)
			(layers "F.Cu" "F.Mask" "F.Paste")
			(net "SSD_PWREN12")
		)
		(pad "16" smd rect
			(at 1.6256 -2.8194)
			(size 0.3556 1.524)
			(layers "F.Cu" "F.Mask" "F.Paste")
			(net "SSD_PERST#12")
		)
		(pad "17" smd rect
			(at 0.97536 -2.8194)
			(size 0.3556 1.524)
			(layers "F.Cu" "F.Mask" "F.Paste")
			(net "SSD_PRSNT#13")
		)
		(pad "18" smd rect
			(at 0.32512 -2.8194)
			(size 0.3556 1.524)
			(layers "F.Cu" "F.Mask" "F.Paste")
			(net "SSD_ATNLED#13")
		)
		(pad "19" smd rect
			(at -0.32512 -2.8194)
			(size 0.3556 1.524)
			(layers "F.Cu" "F.Mask" "F.Paste")
			(net "SSD_PWREN13")
		)
		(pad "20" smd rect
			(at -0.97536 -2.8194)
			(size 0.3556 1.524)
			(layers "F.Cu" "F.Mask" "F.Paste")
			(net "SSD_PERST#13")
		)
		(pad "21" smd rect
			(at -1.6256 -2.8194)
			(size 0.3556 1.524)
			(layers "F.Cu" "F.Mask" "F.Paste")
			(net "IOEXP3_AD0")
		)
		(pad "22" smd rect
			(at -2.27584 -2.8194)
			(size 0.3556 1.524)
			(layers "F.Cu" "F.Mask" "F.Paste")
			(net "I2C_GPIO_SCL_3")
		)
		(pad "23" smd rect
			(at -2.92608 -2.8194)
			(size 0.3556 1.524)
			(layers "F.Cu" "F.Mask" "F.Paste")
			(net "I2C_GPIO_SDA_3")
		)
		(pad "24" smd rect
			(at -3.57632 -2.8194)
			(size 0.3556 1.524)
			(layers "F.Cu" "F.Mask" "F.Paste")
			(net "P3V3_STBY")
		)
	)
	(footprint ""
		(layer "F.Cu")
		(at 344.678 -68.199 180)
		(property "Reference" "PC190"
			(at 0 0 180)
			(layer "F.SilkS")
			(hide yes)
			(effects
				(font
					(size 1.27 1.27)
				)
			)
		)
		(property "Value" "SC1U16V3KX-5GP"
			(at 0 -2.8194 180)
			(unlocked yes)
			(layer "F.Fab")
			(hide yes)
			(effects
				(font
					(size 1.016 1.016)
					(thickness 0.1524)
				)
			)
		)
		(property "Device Type" "C603H36"
			(at 0 -4.3434 180)
			(unlocked yes)
			(layer "F.Fab")
			(hide yes)
			(effects
				(font
					(size 1.016 1.016)
					(thickness 0.1524)
				)
			)
		)
		(duplicate_pad_numbers_are_jumpers no)
		(fp_line
			(start 0.508 0)
			(end -0.508 0)
			(stroke
				(width 0.2032)
				(type default)
			)
			(layer "F.SilkS")
		)
		(fp_rect
			(start -0.5842 1.3335)
			(end 0.5842 -1.3335)
			(stroke
				(width 0)
				(type default)
			)
			(fill no)
			(layer "F.CrtYd")
		)
		(fp_rect
			(start -0.5842 1.3335)
			(end 0.5842 -1.3335)
			(stroke
				(width 0)
				(type default)
			)
			(fill no)
			(layer "F.Fab")
		)
		(pad "1" smd custom
			(at 0 -0.762 180)
			(size 0.2159 0.2159)
			(layers "F.Cu" "F.Mask" "F.Paste")
			(net "P0V9_E_VREG")
			(options
				(clearance outline)
				(anchor circle)
			)
			(primitives
				(gr_poly
					(pts
						(arc
							(start -0.3302 -0.4318)
							(mid -0.402042 -0.402042)
							(end -0.4318 -0.3302)
						)
						(arc
							(start -0.4318 0.3302)
							(mid -0.402042 0.402042)
							(end -0.3302 0.4318)
						)
						(arc
							(start 0.3302 0.4318)
							(mid 0.402042 0.402042)
							(end 0.4318 0.3302)
						)
						(arc
							(start 0.4318 -0.3302)
							(mid 0.402042 -0.402042)
							(end 0.3302 -0.4318)
						)
					)
					(width 0)
					(fill yes)
				)
			)
		)
		(pad "2" smd custom
			(at 0 0.762 180)
			(size 0.2159 0.2159)
			(layers "F.Cu" "F.Mask" "F.Paste")
			(net "GND")
			(options
				(clearance outline)
				(anchor circle)
			)
			(primitives
				(gr_poly
					(pts
						(arc
							(start -0.3302 -0.4318)
							(mid -0.402042 -0.402042)
							(end -0.4318 -0.3302)
						)
						(arc
							(start -0.4318 0.3302)
							(mid -0.402042 0.402042)
							(end -0.3302 0.4318)
						)
						(arc
							(start 0.3302 0.4318)
							(mid 0.402042 0.402042)
							(end 0.4318 0.3302)
						)
						(arc
							(start 0.4318 -0.3302)
							(mid 0.402042 -0.402042)
							(end 0.3302 -0.4318)
						)
					)
					(width 0)
					(fill yes)
				)
			)
		)
	)
	(footprint ""
		(layer "F.Cu")
		(at 325.755 -86.487)
		(property "Reference" "R4166"
			(at 0 0 0)
			(layer "F.SilkS")
			(hide yes)
			(effects
				(font
					(size 1.27 1.27)
				)
			)
		)
		(property "Value" "4K7R2F-GP"
			(at 0.064008 -3.993896 0)
			(unlocked yes)
			(layer "F.Fab")
			(hide yes)
			(effects
				(font
					(size 1.016 1.016)
					(thickness 0.1524)
				)
			)
		)
		(property "Device Type" "R402H16"
			(at 0.064008 -5.517896 0)
			(unlocked yes)
			(layer "F.Fab")
			(hide yes)
			(effects
				(font
					(size 1.016 1.016)
					(thickness 0.1524)
				)
			)
		)
		(duplicate_pad_numbers_are_jumpers no)
		(fp_line
			(start -0.508 -0.9398)
			(end -0.508 0.9398)
			(stroke
				(width 0.1524)
				(type default)
			)
			(layer "F.SilkS")
		)
		(fp_line
			(start 0.508 -0.9398)
			(end -0.508 -0.9398)
			(stroke
				(width 0.1524)
				(type default)
			)
			(layer "F.SilkS")
		)
		(fp_rect
			(start -0.508 0.9398)
			(end 0.508 -0.9398)
			(stroke
				(width 0)
				(type default)
			)
			(fill no)
			(layer "F.CrtYd")
		)
		(fp_rect
			(start -0.508 0.9398)
			(end 0.508 -0.9398)
			(stroke
				(width 0)
				(type default)
			)
			(fill no)
			(layer "F.Fab")
		)
		(pad "1" smd custom
			(at 0 -0.4445)
			(size 0.1397 0.1397)
			(layers "F.Cu" "F.Mask" "F.Paste")
			(net "UPLINK3")
			(options
				(clearance outline)
				(anchor circle)
			)
			(primitives
				(gr_poly
					(pts
						(arc
							(start -0.1778 -0.2794)
							(mid -0.249642 -0.249642)
							(end -0.2794 -0.1778)
						)
						(arc
							(start -0.2794 0.1778)
							(mid -0.249642 0.249642)
							(end -0.1778 0.2794)
						)
						(arc
							(start 0.1778 0.2794)
							(mid 0.249642 0.249642)
							(end 0.2794 0.1778)
						)
						(arc
							(start 0.2794 -0.1778)
							(mid 0.249642 -0.249642)
							(end 0.1778 -0.2794)
						)
					)
					(width 0)
					(fill yes)
				)
			)
		)
		(pad "2" smd custom
			(at 0 0.4445)
			(size 0.1397 0.1397)
			(layers "F.Cu" "F.Mask" "F.Paste")
			(net "P3V3_STBY")
			(options
				(clearance outline)
				(anchor circle)
			)
			(primitives
				(gr_poly
					(pts
						(arc
							(start -0.1778 -0.2794)
							(mid -0.249642 -0.249642)
							(end -0.2794 -0.1778)
						)
						(arc
							(start -0.2794 0.1778)
							(mid -0.249642 0.249642)
							(end -0.1778 0.2794)
						)
						(arc
							(start 0.1778 0.2794)
							(mid 0.249642 0.249642)
							(end 0.2794 0.1778)
						)
						(arc
							(start 0.2794 -0.1778)
							(mid 0.249642 -0.249642)
							(end 0.1778 -0.2794)
						)
					)
					(width 0)
					(fill yes)
				)
			)
		)
	)
	(footprint ""
		(layer "F.Cu")
		(at 74.564748 -123.6726)
		(property "Reference" "U52"
			(at 0 0 0)
			(layer "F.SilkS")
			(hide yes)
			(effects
				(font
					(size 1.27 1.27)
				)
			)
		)
		(property "Value" "SN74LVC1G07DCKRG4-2-GP"
			(at -2.3368 -8.6868 0)
			(unlocked yes)
			(layer "F.Fab")
			(hide yes)
			(effects
				(font
					(size 1.016 1.016)
					(thickness 0.1524)
				)
			)
		)
		(property "Device Type" "SC70-5H44"
			(at -2.3114 -10.414 0)
			(unlocked yes)
			(layer "F.Fab")
			(hide yes)
			(effects
				(font
					(size 1.016 1.016)
					(thickness 0.1524)
				)
			)
		)
		(duplicate_pad_numbers_are_jumpers no)
		(fp_line
			(start -1.27 -1.7018)
			(end 1.27 -1.7018)
			(stroke
				(width 0.1524)
				(type default)
			)
			(layer "F.SilkS")
		)
		(fp_line
			(start -1.27 1.7018)
			(end -1.27 -1.7018)
			(stroke
				(width 0.1524)
				(type default)
			)
			(layer "F.SilkS")
		)
		(fp_line
			(start 0.6604 -1.8034)
			(end 1.3843 -1.8034)
			(stroke
				(width 0.3302)
				(type default)
			)
			(layer "F.SilkS")
		)
		(fp_line
			(start 1.27 -1.7018)
			(end 1.27 1.7018)
			(stroke
				(width 0.1524)
				(type default)
			)
			(layer "F.SilkS")
		)
		(fp_line
			(start 1.27 1.7018)
			(end -1.27 1.7018)
			(stroke
				(width 0.1524)
				(type default)
			)
			(layer "F.SilkS")
		)
		(fp_line
			(start 1.3843 -1.8034)
			(end 1.3843 -1.1176)
			(stroke
				(width 0.3302)
				(type default)
			)
			(layer "F.SilkS")
		)
		(fp_rect
			(start -1.524 1.9558)
			(end 1.524 -1.9558)
			(stroke
				(width 0)
				(type default)
			)
			(fill no)
			(layer "F.CrtYd")
		)
		(fp_poly
			(pts
				(xy -1.524 -1.9558) (xy 1.524 -1.9558) (xy 1.524 1.9558) (xy -1.524 1.9558)
			)
			(stroke
				(width 0)
				(type default)
			)
			(fill no)
			(layer "F.Fab")
		)
		(pad "1" smd rect
			(at 0.65024 -0.8255)
			(size 0.4064 1.2192)
			(layers "F.Cu" "F.Mask" "F.Paste")
			(net "Net_113")
		)
		(pad "2" smd rect
			(at 0 -0.8255)
			(size 0.4064 1.2192)
			(layers "F.Cu" "F.Mask" "F.Paste")
			(net "BMC_RXD5")
		)
		(pad "3" smd rect
			(at -0.65024 -0.8255)
			(size 0.4064 1.2192)
			(layers "F.Cu" "F.Mask" "F.Paste")
			(net "GND")
		)
		(pad "4" smd rect
			(at -0.65024 0.8255)
			(size 0.4064 1.2192)
			(layers "F.Cu" "F.Mask" "F.Paste")
			(net "BMC_RXD5_R")
		)
		(pad "5" smd rect
			(at 0.65024 0.8255)
			(size 0.4064 1.2192)
			(layers "F.Cu" "F.Mask" "F.Paste")
			(net "P3V3_STBY")
		)
	)
	(footprint ""
		(layer "F.Cu")
		(at 323.80809 -212.420454 180)
		(property "Reference" "C65"
			(at 0 0 180)
			(layer "F.SilkS")
			(hide yes)
			(effects
				(font
					(size 1.27 1.27)
				)
			)
		)
		(property "Value" "SCD22U10V2KX-1GP"
			(at 1.1811 -2.7051 180)
			(unlocked yes)
			(layer "F.Fab")
			(hide yes)
			(effects
				(font
					(size 1.016 1.016)
					(thickness 0.1524)
				)
			)
		)
		(property "Device Type" "C402H22"
			(at 1.1811 -4.2291 180)
			(unlocked yes)
			(layer "F.Fab")
			(hide yes)
			(effects
				(font
					(size 1.016 1.016)
					(thickness 0.1524)
				)
			)
		)
		(duplicate_pad_numbers_are_jumpers no)
		(fp_rect
			(start -0.4318 0.9525)
			(end 0.4318 -0.9525)
			(stroke
				(width 0)
				(type default)
			)
			(fill no)
			(layer "F.CrtYd")
		)
		(fp_rect
			(start -0.4318 0.9525)
			(end 0.4318 -0.9525)
			(stroke
				(width 0)
				(type default)
			)
			(fill no)
			(layer "F.Fab")
		)
		(pad "1" smd custom
			(at 0 -0.4445 180)
			(size 0.1524 0.1524)
			(layers "F.Cu" "F.Mask" "F.Paste")
			(net "PCIE_TX_CAP_N21")
			(options
				(clearance outline)
				(anchor circle)
			)
			(primitives
				(gr_poly
					(pts
						(arc
							(start 0.3048 -0.2032)
							(mid 0.275042 -0.275042)
							(end 0.2032 -0.3048)
						)
						(arc
							(start -0.2032 -0.3048)
							(mid -0.275042 -0.275042)
							(end -0.3048 -0.2032)
						)
						(arc
							(start -0.3048 0.2032)
							(mid -0.275042 0.275042)
							(end -0.2032 0.3048)
						)
						(arc
							(start 0.2032 0.3048)
							(mid 0.275042 0.275042)
							(end 0.3048 0.2032)
						)
					)
					(width 0)
					(fill yes)
				)
			)
		)
		(pad "2" smd custom
			(at 0 0.4445 180)
			(size 0.1524 0.1524)
			(layers "F.Cu" "F.Mask" "F.Paste")
			(net "PCIE_TX_N21")
			(options
				(clearance outline)
				(anchor circle)
			)
			(primitives
				(gr_poly
					(pts
						(arc
							(start 0.3048 -0.2032)
							(mid 0.275042 -0.275042)
							(end 0.2032 -0.3048)
						)
						(arc
							(start -0.2032 -0.3048)
							(mid -0.275042 -0.275042)
							(end -0.3048 -0.2032)
						)
						(arc
							(start -0.3048 0.2032)
							(mid -0.275042 0.275042)
							(end -0.2032 0.3048)
						)
						(arc
							(start 0.2032 0.3048)
							(mid 0.275042 0.275042)
							(end 0.3048 0.2032)
						)
					)
					(width 0)
					(fill yes)
				)
			)
		)
	)
)
